FILE_TYPE = CONNECTIVITY;
{Allegro Design Entry HDL 17.2-2016 S081 (4005846) 1/11/2022}
"PAGE_NUMBER" = 155;
0"NC";
END.
